# T6G (Grand Teton) — schematic netlist excerpt (pin names and nets, part order shuffled) for the footprints in the layout excerpt that follows; sources: Cadence DE-HDL packaged netlist, KiCad conversion of 04192023_DAF0TMB3IC0_F0TG_MB_C_brd_V02_OCP.brd

C24  Q_CAP  10UF 6.3V 20% EMPTY  pkg C0402  page 161 : A = PVDD18_S5_P0 ; B = GND
R797  Q_RES  0 5% CHIP  pkg 0201LF  page 185 : A = SMB_RT_CPU0_P0_ROM_MUX_2D_R_SDA ; B = SMB_RT_CPU0_P0_ROM_MUX_2D_SDA
PC159_2  Q_CAP  22UF 16V 20% X6S  pkg C0805  page 205 : A = SW_P12V_AUX_PVDDIO_P0_FLT ; B = GND
R1021  Q_RES  4.7K 5% EMPTY  pkg 0201LF  page 287 : A = P1V8_CPU0_RT_1D ; B = RT_CPU0_P1_SCAN_MODE

(kicad_pcb
	(version 20260206)
	(generator "pcbnew")
	(generator_version "10.0")
	(general
		(thickness 1.6)
		(legacy_teardrops no)
	)
	(paper "A4")
	(title_block
		(title "04192023_DAF0TMB3IC0_F0TG_MB_C_brd_V02_OCP.brd")
		(comment 1 "Grand Teton / footprints 5183-5186 of 8354")
	)
	(layers
		(0 "F.Cu" signal "TOP")
		(4 "In1.Cu" signal "GND")
		(6 "In2.Cu" signal "IN1")
		(8 "In3.Cu" signal "GND1")
		(10 "In4.Cu" signal "IN2")
		(12 "In5.Cu" signal "GND2")
		(14 "In6.Cu" signal "IN3")
		(16 "In7.Cu" signal "GND3")
		(18 "In8.Cu" signal "VCC")
		(20 "In9.Cu" signal "VCC1")
		(22 "In10.Cu" signal "GND4")
		(24 "In11.Cu" signal "IN4")
		(26 "In12.Cu" signal "GND5")
		(28 "In13.Cu" signal "IN5")
		(30 "In14.Cu" signal "GND6")
		(32 "In15.Cu" signal "IN6")
		(34 "In16.Cu" signal "GND7")
		(2 "B.Cu" signal "BOTTOM")
		(9 "F.Adhes" user "F.Adhesive")
		(11 "B.Adhes" user "B.Adhesive")
		(13 "F.Paste" user "Package Geometry/Pastemask Top")
		(15 "B.Paste" user "Package Geometry/Pastemask Bottom")
		(5 "F.SilkS" user "Ref Des/Silkscreen Top")
		(7 "B.SilkS" user "Ref Des/Silkscreen Bottom")
		(1 "F.Mask" user "Board Geometry/Soldermask Top")
		(3 "B.Mask" user "Board Geometry/Soldermask Bottom")
		(17 "Dwgs.User" user "User.Drawings")
		(19 "Cmts.User" user "User.Comments")
		(21 "Eco1.User" user "User.Eco1")
		(23 "Eco2.User" user "User.Eco2")
		(25 "Edge.Cuts" user "Board Geometry/Outline")
		(27 "Margin" user)
		(31 "F.CrtYd" user "Package Geometry/Place Bound Top")
		(29 "B.CrtYd" user "Package Geometry/Place Bound Bottom")
		(35 "F.Fab" user "Ref Des/Assembly Top")
		(33 "B.Fab" user "Ref Des/Assembly Bottom")
	)
	(footprint ""
		(layer "B.Cu")
		(at 295.257982 -346.784168 90)
		(property "Reference" "PC159_2"
			(at 0 0 90)
			(layer "B.SilkS")
			(hide yes)
			(effects
				(font
					(size 1.27 1.27)
				)
				(justify mirror)
			)
		)
		(property "Value" ""
			(at 0 0 90)
			(layer "B.Fab")
			(effects
				(font
					(size 1.27 1.27)
				)
				(justify mirror)
			)
		)
		(duplicate_pad_numbers_are_jumpers no)
		(fp_line
			(start 1.524 -0.762)
			(end -1.524 -0.762)
			(stroke
				(width 0.1524)
				(type default)
			)
			(layer "B.SilkS")
		)
		(fp_line
			(start -1.524 -0.762)
			(end -1.524 0.762)
			(stroke
				(width 0.1524)
				(type default)
			)
			(layer "B.SilkS")
		)
		(fp_line
			(start 1.524 0.762)
			(end 1.524 -0.762)
			(stroke
				(width 0.1524)
				(type default)
			)
			(layer "B.SilkS")
		)
		(fp_line
			(start -1.524 0.762)
			(end 1.524 0.762)
			(stroke
				(width 0.1524)
				(type default)
			)
			(layer "B.SilkS")
		)
		(fp_line
			(start 1.1049 -0.724916)
			(end 1.1049 0.724916)
			(stroke
				(width 0.1)
				(type default)
			)
			(layer "B.Fab")
		)
		(fp_line
			(start -1.1049 -0.724916)
			(end 1.1049 -0.724916)
			(stroke
				(width 0.1)
				(type default)
			)
			(layer "B.Fab")
		)
		(fp_line
			(start 1.1049 0.724916)
			(end -1.1049 0.724916)
			(stroke
				(width 0.1)
				(type default)
			)
			(layer "B.Fab")
		)
		(fp_line
			(start -1.1049 0.724916)
			(end -1.1049 -0.724916)
			(stroke
				(width 0.1)
				(type default)
			)
			(layer "B.Fab")
		)
		(pad "1" smd rect
			(at 0.889 0 90)
			(size 1.016 1.27)
			(layers "B.Cu" "B.Mask" "B.Paste")
			(net "SW_P12V_AUX_PVDDIO_P0_FLT")
		)
		(pad "2" smd rect
			(at -0.889 0 90)
			(size 1.016 1.27)
			(layers "B.Cu" "B.Mask" "B.Paste")
			(net "GND")
		)
	)
	(footprint ""
		(layer "B.Cu")
		(at 233.172 -234.569 -90)
		(property "Reference" "C24"
			(at 0 0 90)
			(layer "B.SilkS")
			(hide yes)
			(effects
				(font
					(size 1.27 1.27)
				)
				(justify mirror)
			)
		)
		(property "Value" ""
			(at 0 0 90)
			(layer "B.Fab")
			(effects
				(font
					(size 1.27 1.27)
				)
				(justify mirror)
			)
		)
		(duplicate_pad_numbers_are_jumpers no)
		(fp_line
			(start -0.7874 0.4064)
			(end 0.7874 0.4064)
			(stroke
				(width 0.1524)
				(type default)
			)
			(layer "B.SilkS")
		)
		(fp_line
			(start 0.7874 0.4064)
			(end 0.7874 -0.4064)
			(stroke
				(width 0.1524)
				(type default)
			)
			(layer "B.SilkS")
		)
		(fp_line
			(start -0.7874 -0.4064)
			(end -0.7874 0.4064)
			(stroke
				(width 0.1524)
				(type default)
			)
			(layer "B.SilkS")
		)
		(fp_line
			(start 0.7874 -0.4064)
			(end -0.7874 -0.4064)
			(stroke
				(width 0.1524)
				(type default)
			)
			(layer "B.SilkS")
		)
		(fp_line
			(start -0.67945 0.3048)
			(end -0.120396 0.3048)
			(stroke
				(width 0.1)
				(type default)
			)
			(layer "B.Fab")
		)
		(fp_line
			(start -0.120396 0.3048)
			(end -0.120396 0.2794)
			(stroke
				(width 0.1)
				(type default)
			)
			(layer "B.Fab")
		)
		(fp_line
			(start 0.12065 0.3048)
			(end 0.67945 0.3048)
			(stroke
				(width 0.1)
				(type default)
			)
			(layer "B.Fab")
		)
		(fp_line
			(start 0.67945 0.3048)
			(end 0.67945 -0.305054)
			(stroke
				(width 0.1)
				(type default)
			)
			(layer "B.Fab")
		)
		(fp_line
			(start -0.120396 0.2794)
			(end 0.12065 0.2794)
			(stroke
				(width 0.1)
				(type default)
			)
			(layer "B.Fab")
		)
		(fp_line
			(start 0.12065 0.2794)
			(end 0.12065 0.3048)
			(stroke
				(width 0.1)
				(type default)
			)
			(layer "B.Fab")
		)
		(fp_line
			(start -0.12065 -0.2794)
			(end -0.12065 -0.3048)
			(stroke
				(width 0.1)
				(type default)
			)
			(layer "B.Fab")
		)
		(fp_line
			(start 0.12065 -0.2794)
			(end -0.12065 -0.2794)
			(stroke
				(width 0.1)
				(type default)
			)
			(layer "B.Fab")
		)
		(fp_line
			(start -0.67945 -0.3048)
			(end -0.67945 0.3048)
			(stroke
				(width 0.1)
				(type default)
			)
			(layer "B.Fab")
		)
		(fp_line
			(start -0.12065 -0.3048)
			(end -0.67945 -0.3048)
			(stroke
				(width 0.1)
				(type default)
			)
			(layer "B.Fab")
		)
		(fp_line
			(start 0.12065 -0.305054)
			(end 0.12065 -0.2794)
			(stroke
				(width 0.1)
				(type default)
			)
			(layer "B.Fab")
		)
		(fp_line
			(start 0.67945 -0.305054)
			(end 0.12065 -0.305054)
			(stroke
				(width 0.1)
				(type default)
			)
			(layer "B.Fab")
		)
		(pad "1" smd circle
			(at 0.40005 0 90)
			(size 0 0)
			(layers "B.Cu" "B.Mask" "B.Paste")
			(net "PVDD18_S5_P0")
		)
		(pad "2" smd circle
			(at -0.40005 0 90)
			(size 0 0)
			(layers "B.Cu" "B.Mask" "B.Paste")
			(net "GND")
		)
	)
	(footprint ""
		(layer "B.Cu")
		(at 255.905 -341.884 180)
		(property "Reference" "R797"
			(at 0 0 0)
			(layer "B.SilkS")
			(hide yes)
			(effects
				(font
					(size 1.27 1.27)
				)
				(justify mirror)
			)
		)
		(property "Value" ""
			(at 0 0 0)
			(layer "B.Fab")
			(effects
				(font
					(size 1.27 1.27)
				)
				(justify mirror)
			)
		)
		(duplicate_pad_numbers_are_jumpers no)
		(fp_line
			(start 0.32512 0.175006)
			(end 0.32512 -0.175006)
			(stroke
				(width 0.1)
				(type default)
			)
			(layer "B.Fab")
		)
		(fp_line
			(start 0.32512 -0.175006)
			(end -0.32512 -0.175006)
			(stroke
				(width 0.1)
				(type default)
			)
			(layer "B.Fab")
		)
		(fp_line
			(start -0.32512 0.175006)
			(end 0.32512 0.175006)
			(stroke
				(width 0.1)
				(type default)
			)
			(layer "B.Fab")
		)
		(fp_line
			(start -0.32512 -0.175006)
			(end -0.32512 0.175006)
			(stroke
				(width 0.1)
				(type default)
			)
			(layer "B.Fab")
		)
		(pad "1" smd rect
			(at 0.2667 0)
			(size 0.3048 0.381)
			(layers "B.Cu" "B.Mask" "B.Paste")
			(net "SMB_RT_CPU0_P0_ROM_MUX_2D_R_SDA")
		)
		(pad "2" smd rect
			(at -0.2667 0 180)
			(size 0.3048 0.381)
			(layers "B.Cu" "B.Mask" "B.Paste")
			(net "SMB_RT_CPU0_P0_ROM_MUX_2D_SDA")
		)
	)
	(footprint ""
		(layer "B.Cu")
		(at 330.523342 -392.1252 180)
		(property "Reference" "R1021"
			(at 0 0 0)
			(layer "B.SilkS")
			(hide yes)
			(effects
				(font
					(size 1.27 1.27)
				)
				(justify mirror)
			)
		)
		(property "Value" ""
			(at 0 0 0)
			(layer "B.Fab")
			(effects
				(font
					(size 1.27 1.27)
				)
				(justify mirror)
			)
		)
		(duplicate_pad_numbers_are_jumpers no)
		(fp_line
			(start 0.32512 0.175006)
			(end 0.32512 -0.175006)
			(stroke
				(width 0.1)
				(type default)
			)
			(layer "B.Fab")
		)
		(fp_line
			(start 0.32512 -0.175006)
			(end -0.32512 -0.175006)
			(stroke
				(width 0.1)
				(type default)
			)
			(layer "B.Fab")
		)
		(fp_line
			(start -0.32512 0.175006)
			(end 0.32512 0.175006)
			(stroke
				(width 0.1)
				(type default)
			)
			(layer "B.Fab")
		)
		(fp_line
			(start -0.32512 -0.175006)
			(end -0.32512 0.175006)
			(stroke
				(width 0.1)
				(type default)
			)
			(layer "B.Fab")
		)
		(pad "1" smd rect
			(at 0.2667 0)
			(size 0.3048 0.381)
			(layers "B.Cu" "B.Mask" "B.Paste")
			(net "P1V8_CPU0_RT_1D")
		)
		(pad "2" smd rect
			(at -0.2667 0 180)
			(size 0.3048 0.381)
			(layers "B.Cu" "B.Mask" "B.Paste")
			(net "RT_CPU0_P1_SCAN_MODE")
		)
	)
)
